# T6G (Grand Teton) — schematic netlist excerpt (pin names and nets, part order shuffled) for the footprints in the layout excerpt that follows; sources: Cadence DE-HDL packaged netlist, KiCad conversion of 04192023_DAF0TMB3IC0_F0TG_MB_C_brd_V02_OCP.brd

R739  Q_RES  10K 5% EMPTY  pkg 0402LF  page 76 : A = PVDD18_S5_P0 ; B = CLK_ESPI_CPU0_CLK1
C2498  Q_CAP  22UF 4V 20% X6S  pkg C0402  page 74 : A = PVDDIO_P1 ; B = GND

(kicad_pcb
	(version 20260206)
	(generator "pcbnew")
	(generator_version "10.0")
	(general
		(thickness 1.6)
		(legacy_teardrops no)
	)
	(paper "A4")
	(title_block
		(title "04192023_DAF0TMB3IC0_F0TG_MB_C_brd_V02_OCP.brd")
		(comment 1 "Grand Teton / footprints 5932-5933 of 8354")
	)
	(layers
		(0 "F.Cu" signal "TOP")
		(4 "In1.Cu" signal "GND")
		(6 "In2.Cu" signal "IN1")
		(8 "In3.Cu" signal "GND1")
		(10 "In4.Cu" signal "IN2")
		(12 "In5.Cu" signal "GND2")
		(14 "In6.Cu" signal "IN3")
		(16 "In7.Cu" signal "GND3")
		(18 "In8.Cu" signal "VCC")
		(20 "In9.Cu" signal "VCC1")
		(22 "In10.Cu" signal "GND4")
		(24 "In11.Cu" signal "IN4")
		(26 "In12.Cu" signal "GND5")
		(28 "In13.Cu" signal "IN5")
		(30 "In14.Cu" signal "GND6")
		(32 "In15.Cu" signal "IN6")
		(34 "In16.Cu" signal "GND7")
		(2 "B.Cu" signal "BOTTOM")
		(9 "F.Adhes" user "F.Adhesive")
		(11 "B.Adhes" user "B.Adhesive")
		(13 "F.Paste" user "Package Geometry/Pastemask Top")
		(15 "B.Paste" user "Package Geometry/Pastemask Bottom")
		(5 "F.SilkS" user "Ref Des/Silkscreen Top")
		(7 "B.SilkS" user "Ref Des/Silkscreen Bottom")
		(1 "F.Mask" user "Board Geometry/Soldermask Top")
		(3 "B.Mask" user "Board Geometry/Soldermask Bottom")
		(17 "Dwgs.User" user "User.Drawings")
		(19 "Cmts.User" user "User.Comments")
		(21 "Eco1.User" user "User.Eco1")
		(23 "Eco2.User" user "User.Eco2")
		(25 "Edge.Cuts" user "Board Geometry/Outline")
		(27 "Margin" user)
		(31 "F.CrtYd" user "Package Geometry/Place Bound Top")
		(29 "B.CrtYd" user "Package Geometry/Place Bound Bottom")
		(35 "F.Fab" user "Ref Des/Assembly Top")
		(33 "B.Fab" user "Ref Des/Assembly Bottom")
	)
	(footprint ""
		(layer "B.Cu")
		(at 100.497386 -256.734564 180)
		(property "Reference" "C2498"
			(at 0 0 0)
			(layer "B.SilkS")
			(hide yes)
			(effects
				(font
					(size 1.27 1.27)
				)
				(justify mirror)
			)
		)
		(property "Value" ""
			(at 0 0 0)
			(layer "B.Fab")
			(effects
				(font
					(size 1.27 1.27)
				)
				(justify mirror)
			)
		)
		(duplicate_pad_numbers_are_jumpers no)
		(fp_line
			(start 0.7874 0.4064)
			(end 0.7874 -0.4064)
			(stroke
				(width 0.1524)
				(type default)
			)
			(layer "B.SilkS")
		)
		(fp_line
			(start 0.7874 -0.4064)
			(end -0.7874 -0.4064)
			(stroke
				(width 0.1524)
				(type default)
			)
			(layer "B.SilkS")
		)
		(fp_line
			(start -0.7874 0.4064)
			(end 0.7874 0.4064)
			(stroke
				(width 0.1524)
				(type default)
			)
			(layer "B.SilkS")
		)
		(fp_line
			(start -0.7874 -0.4064)
			(end -0.7874 0.4064)
			(stroke
				(width 0.1524)
				(type default)
			)
			(layer "B.SilkS")
		)
		(fp_line
			(start 0.67945 0.3048)
			(end 0.67945 -0.305054)
			(stroke
				(width 0.1)
				(type default)
			)
			(layer "B.Fab")
		)
		(fp_line
			(start 0.67945 -0.305054)
			(end 0.12065 -0.305054)
			(stroke
				(width 0.1)
				(type default)
			)
			(layer "B.Fab")
		)
		(fp_line
			(start 0.12065 0.3048)
			(end 0.67945 0.3048)
			(stroke
				(width 0.1)
				(type default)
			)
			(layer "B.Fab")
		)
		(fp_line
			(start 0.12065 0.2794)
			(end 0.12065 0.3048)
			(stroke
				(width 0.1)
				(type default)
			)
			(layer "B.Fab")
		)
		(fp_line
			(start 0.12065 -0.2794)
			(end -0.12065 -0.2794)
			(stroke
				(width 0.1)
				(type default)
			)
			(layer "B.Fab")
		)
		(fp_line
			(start 0.12065 -0.305054)
			(end 0.12065 -0.2794)
			(stroke
				(width 0.1)
				(type default)
			)
			(layer "B.Fab")
		)
		(fp_line
			(start -0.120396 0.3048)
			(end -0.120396 0.2794)
			(stroke
				(width 0.1)
				(type default)
			)
			(layer "B.Fab")
		)
		(fp_line
			(start -0.120396 0.2794)
			(end 0.12065 0.2794)
			(stroke
				(width 0.1)
				(type default)
			)
			(layer "B.Fab")
		)
		(fp_line
			(start -0.12065 -0.2794)
			(end -0.12065 -0.3048)
			(stroke
				(width 0.1)
				(type default)
			)
			(layer "B.Fab")
		)
		(fp_line
			(start -0.12065 -0.3048)
			(end -0.67945 -0.3048)
			(stroke
				(width 0.1)
				(type default)
			)
			(layer "B.Fab")
		)
		(fp_line
			(start -0.67945 0.3048)
			(end -0.120396 0.3048)
			(stroke
				(width 0.1)
				(type default)
			)
			(layer "B.Fab")
		)
		(fp_line
			(start -0.67945 -0.3048)
			(end -0.67945 0.3048)
			(stroke
				(width 0.1)
				(type default)
			)
			(layer "B.Fab")
		)
		(pad "1" smd circle
			(at 0.40005 0)
			(size 0 0)
			(layers "B.Cu" "B.Mask" "B.Paste")
			(net "PVDDIO_P1")
		)
		(pad "2" smd circle
			(at -0.40005 0)
			(size 0 0)
			(layers "B.Cu" "B.Mask" "B.Paste")
			(net "GND")
		)
	)
	(footprint ""
		(layer "B.Cu")
		(at 393.637008 -322.195952)
		(property "Reference" "R739"
			(at 0 0 0)
			(layer "B.SilkS")
			(hide yes)
			(effects
				(font
					(size 1.27 1.27)
				)
				(justify mirror)
			)
		)
		(property "Value" ""
			(at 0 0 0)
			(layer "B.Fab")
			(effects
				(font
					(size 1.27 1.27)
				)
				(justify mirror)
			)
		)
		(duplicate_pad_numbers_are_jumpers no)
		(fp_line
			(start -0.7874 -0.4064)
			(end -0.7874 0.4064)
			(stroke
				(width 0.1524)
				(type default)
			)
			(layer "B.SilkS")
		)
		(fp_line
			(start -0.7874 0.4064)
			(end 0.7874 0.4064)
			(stroke
				(width 0.1524)
				(type default)
			)
			(layer "B.SilkS")
		)
		(fp_line
			(start 0.7874 -0.4064)
			(end -0.7874 -0.4064)
			(stroke
				(width 0.1524)
				(type default)
			)
			(layer "B.SilkS")
		)
		(fp_line
			(start 0.7874 0.4064)
			(end 0.7874 -0.4064)
			(stroke
				(width 0.1524)
				(type default)
			)
			(layer "B.SilkS")
		)
		(fp_line
			(start -0.67945 -0.3048)
			(end -0.67945 0.3048)
			(stroke
				(width 0.1)
				(type default)
			)
			(layer "B.Fab")
		)
		(fp_line
			(start -0.67945 0.3048)
			(end -0.120396 0.3048)
			(stroke
				(width 0.1)
				(type default)
			)
			(layer "B.Fab")
		)
		(fp_line
			(start -0.12065 -0.3048)
			(end -0.67945 -0.3048)
			(stroke
				(width 0.1)
				(type default)
			)
			(layer "B.Fab")
		)
		(fp_line
			(start -0.12065 -0.2794)
			(end -0.12065 -0.3048)
			(stroke
				(width 0.1)
				(type default)
			)
			(layer "B.Fab")
		)
		(fp_line
			(start -0.120396 0.2794)
			(end 0.12065 0.2794)
			(stroke
				(width 0.1)
				(type default)
			)
			(layer "B.Fab")
		)
		(fp_line
			(start -0.120396 0.3048)
			(end -0.120396 0.2794)
			(stroke
				(width 0.1)
				(type default)
			)
			(layer "B.Fab")
		)
		(fp_line
			(start 0.12065 -0.305054)
			(end 0.12065 -0.2794)
			(stroke
				(width 0.1)
				(type default)
			)
			(layer "B.Fab")
		)
		(fp_line
			(start 0.12065 -0.2794)
			(end -0.12065 -0.2794)
			(stroke
				(width 0.1)
				(type default)
			)
			(layer "B.Fab")
		)
		(fp_line
			(start 0.12065 0.2794)
			(end 0.12065 0.3048)
			(stroke
				(width 0.1)
				(type default)
			)
			(layer "B.Fab")
		)
		(fp_line
			(start 0.12065 0.3048)
			(end 0.67945 0.3048)
			(stroke
				(width 0.1)
				(type default)
			)
			(layer "B.Fab")
		)
		(fp_line
			(start 0.67945 -0.305054)
			(end 0.12065 -0.305054)
			(stroke
				(width 0.1)
				(type default)
			)
			(layer "B.Fab")
		)
		(fp_line
			(start 0.67945 0.3048)
			(end 0.67945 -0.305054)
			(stroke
				(width 0.1)
				(type default)
			)
			(layer "B.Fab")
		)
		(pad "1" smd circle
			(at 0.40005 0 180)
			(size 0 0)
			(layers "B.Cu" "B.Mask" "B.Paste")
			(net "PVDD18_S5_P0")
		)
		(pad "2" smd circle
			(at -0.40005 0 180)
			(size 0 0)
			(layers "B.Cu" "B.Mask" "B.Paste")
			(net "CLK_ESPI_CPU0_CLK1")
		)
	)
)
